(kicad_pcb
	(version 20260206)
	(generator "pcbnew")
	(generator_version "10.0")
	(general
		(thickness 1.6)
		(legacy_teardrops no)
	)
	(paper "A4")
	(title_block
		(title "Wiwynn_Tioga_Pass_MB.brd")
		(comment 1 "Tioga Pass / footprints 4601-4607 of 4770")
	)
	(layers
		(0 "F.Cu" signal "TOP")
		(4 "In1.Cu" signal "L2GND")
		(6 "In2.Cu" signal "L3")
		(8 "In3.Cu" signal "L4GND")
		(10 "In4.Cu" signal "L5")
		(12 "In5.Cu" signal "L6GND")
		(14 "In6.Cu" signal "L7VCC")
		(16 "In7.Cu" signal "L8VCC")
		(18 "In8.Cu" signal "L9GND")
		(20 "In9.Cu" signal "L10")
		(22 "In10.Cu" signal "L11GND")
		(24 "In11.Cu" signal "L12")
		(26 "In12.Cu" signal "L13GND")
		(2 "B.Cu" signal "BOTTOM")
		(9 "F.Adhes" user "F.Adhesive")
		(11 "B.Adhes" user "B.Adhesive")
		(13 "F.Paste" user "Package Geometry/Pastemask Top")
		(15 "B.Paste" user "Package Geometry/Pastemask Bottom")
		(5 "F.SilkS" user "Ref Des/Silkscreen Top")
		(7 "B.SilkS" user "Ref Des/Silkscreen Bottom")
		(1 "F.Mask" user "Board Geometry/Soldermask Top")
		(3 "B.Mask" user "Board Geometry/Soldermask Bottom")
		(17 "Dwgs.User" user "User.Drawings")
		(19 "Cmts.User" user "User.Comments")
		(21 "Eco1.User" user "User.Eco1")
		(23 "Eco2.User" user "User.Eco2")
		(25 "Edge.Cuts" user "Board Geometry/Outline")
		(27 "Margin" user)
		(31 "F.CrtYd" user "Package Geometry/Place Bound Top")
		(29 "B.CrtYd" user "Package Geometry/Place Bound Bottom")
		(35 "F.Fab" user "Ref Des/Assembly Top")
		(33 "B.Fab" user "Ref Des/Assembly Bottom")
	)
	(footprint ""
		(layer "B.Cu")
		(at 443.0522 -64.7446 180)
		(property "Reference" "C2P16"
			(at 0 0 0)
			(layer "B.SilkS")
			(hide yes)
			(effects
				(font
					(size 1.27 1.27)
				)
				(justify mirror)
			)
		)
		(property "Value" ""
			(at 0 0 0)
			(layer "B.Fab")
			(effects
				(font
					(size 1.27 1.27)
				)
				(justify mirror)
			)
		)
		(duplicate_pad_numbers_are_jumpers no)
		(fp_poly
			(pts
				(xy -0.3048 -0.1016) (xy -0.3048 0.9906) (xy 0.3048 0.9906) (xy 0.3048 -0.1016)
			)
			(stroke
				(width 0)
				(type default)
			)
			(fill no)
			(layer "B.CrtYd")
		)
		(fp_line
			(start 0.3048 0.9906)
			(end -0.3048 0.9906)
			(stroke
				(width 0.1)
				(type default)
			)
			(layer "B.Fab")
		)
		(fp_line
			(start 0.3048 -0.1016)
			(end 0.3048 0.9906)
			(stroke
				(width 0.1)
				(type default)
			)
			(layer "B.Fab")
		)
		(fp_line
			(start -0.3048 0.9906)
			(end -0.3048 -0.1016)
			(stroke
				(width 0.1)
				(type default)
			)
			(layer "B.Fab")
		)
		(fp_line
			(start -0.3048 -0.1016)
			(end 0.3048 -0.1016)
			(stroke
				(width 0.1)
				(type default)
			)
			(layer "B.Fab")
		)
		(pad "1" smd rect
			(at 0 0)
			(size 0.508 0.508)
			(layers "B.Cu" "B.Mask" "B.Paste")
			(net "P12V_STBY")
		)
		(pad "2" smd rect
			(at 0 0.889)
			(size 0.508 0.508)
			(layers "B.Cu" "B.Mask" "B.Paste")
			(net "GND")
		)
		(zone
			(layer "B.Cu")
			(hatch none 0.5)
			(connect_pads
				(clearance 0)
			)
			(min_thickness 0.25)
			(keepout
				(tracks not_allowed)
				(vias allowed)
				(pads allowed)
				(copperpour not_allowed)
				(footprints allowed)
			)
			(placement
				(enabled no)
				(sheetname "")
			)
			(fill
				(thermal_gap 0.5)
				(thermal_bridge_width 0.5)
				(island_removal_mode 0)
			)
			(polygon
				(pts
					(xy 442.7982 -65.3796) (xy 443.3062 -65.3796) (xy 443.3062 -64.9986) (xy 442.7982 -64.9986)
				)
			)
		)
		(zone
			(layer "B.Cu")
			(hatch none 0.5)
			(connect_pads
				(clearance 0)
			)
			(min_thickness 0.25)
			(keepout
				(tracks allowed)
				(vias not_allowed)
				(pads allowed)
				(copperpour not_allowed)
				(footprints allowed)
			)
			(placement
				(enabled no)
				(sheetname "")
			)
			(fill
				(thermal_gap 0.5)
				(thermal_bridge_width 0.5)
				(island_removal_mode 0)
			)
			(polygon
				(pts
					(xy 442.7982 -64.9986) (xy 443.3062 -64.9986) (xy 443.3062 -65.3796) (xy 442.7982 -65.3796)
				)
			)
		)
	)
	(footprint ""
		(layer "B.Cu")
		(at 397.764 -75.1967 -90)
		(property "Reference" "C6W4"
			(at 0.8382 -0.67818 270)
			(unlocked yes)
			(layer "B.SilkS")
			(effects
				(font
					(size 0.4064 0.254)
					(thickness 0.1524)
				)
				(justify left mirror)
			)
		)
		(property "Value" ""
			(at 0 0 90)
			(layer "B.Fab")
			(effects
				(font
					(size 1.27 1.27)
				)
				(justify mirror)
			)
		)
		(duplicate_pad_numbers_are_jumpers no)
		(fp_poly
			(pts
				(xy -0.3048 -0.1016) (xy -0.3048 0.9906) (xy 0.3048 0.9906) (xy 0.3048 -0.1016)
			)
			(stroke
				(width 0)
				(type default)
			)
			(fill no)
			(layer "B.CrtYd")
		)
		(fp_line
			(start -0.3048 0.9906)
			(end -0.3048 -0.1016)
			(stroke
				(width 0.1)
				(type default)
			)
			(layer "B.Fab")
		)
		(fp_line
			(start 0.3048 0.9906)
			(end -0.3048 0.9906)
			(stroke
				(width 0.1)
				(type default)
			)
			(layer "B.Fab")
		)
		(fp_line
			(start -0.3048 -0.1016)
			(end 0.3048 -0.1016)
			(stroke
				(width 0.1)
				(type default)
			)
			(layer "B.Fab")
		)
		(fp_line
			(start 0.3048 -0.1016)
			(end 0.3048 0.9906)
			(stroke
				(width 0.1)
				(type default)
			)
			(layer "B.Fab")
		)
		(pad "1" smd rect
			(at 0 0 90)
			(size 0.508 0.508)
			(layers "B.Cu" "B.Mask" "B.Paste")
			(net "P3V3_STBY")
		)
		(pad "2" smd rect
			(at 0 0.889 90)
			(size 0.508 0.508)
			(layers "B.Cu" "B.Mask" "B.Paste")
			(net "GND")
		)
		(zone
			(layer "B.Cu")
			(hatch none 0.5)
			(connect_pads
				(clearance 0)
			)
			(min_thickness 0.25)
			(keepout
				(tracks not_allowed)
				(vias allowed)
				(pads allowed)
				(copperpour not_allowed)
				(footprints allowed)
			)
			(placement
				(enabled no)
				(sheetname "")
			)
			(fill
				(thermal_gap 0.5)
				(thermal_bridge_width 0.5)
				(island_removal_mode 0)
			)
			(polygon
				(pts
					(xy 397.129 -74.9427) (xy 397.129 -75.4507) (xy 397.51 -75.4507) (xy 397.51 -74.9427)
				)
			)
		)
		(zone
			(layer "B.Cu")
			(hatch none 0.5)
			(connect_pads
				(clearance 0)
			)
			(min_thickness 0.25)
			(keepout
				(tracks allowed)
				(vias not_allowed)
				(pads allowed)
				(copperpour not_allowed)
				(footprints allowed)
			)
			(placement
				(enabled no)
				(sheetname "")
			)
			(fill
				(thermal_gap 0.5)
				(thermal_bridge_width 0.5)
				(island_removal_mode 0)
			)
			(polygon
				(pts
					(xy 397.51 -74.9427) (xy 397.51 -75.4507) (xy 397.129 -75.4507) (xy 397.129 -74.9427)
				)
			)
		)
	)
	(footprint ""
		(layer "B.Cu")
		(at 95.377254 -73.51014)
		(property "Reference" "C8P28"
			(at 0 0 0)
			(layer "B.SilkS")
			(hide yes)
			(effects
				(font
					(size 1.27 1.27)
				)
				(justify mirror)
			)
		)
		(property "Value" ""
			(at 0 0 0)
			(layer "B.Fab")
			(effects
				(font
					(size 1.27 1.27)
				)
				(justify mirror)
			)
		)
		(duplicate_pad_numbers_are_jumpers no)
		(fp_poly
			(pts
				(xy 0.7239 -0.2159) (xy -0.7239 -0.2159) (xy -0.7239 1.9939) (xy 0.7239 1.9939)
			)
			(stroke
				(width 0)
				(type default)
			)
			(fill no)
			(layer "B.CrtYd")
		)
		(fp_line
			(start -0.7239 -0.2159)
			(end 0.7239 -0.2159)
			(stroke
				(width 0.1)
				(type default)
			)
			(layer "B.Fab")
		)
		(fp_line
			(start -0.7239 1.9939)
			(end -0.7239 -0.2159)
			(stroke
				(width 0.1)
				(type default)
			)
			(layer "B.Fab")
		)
		(fp_line
			(start 0.7239 -0.2159)
			(end 0.7239 1.9939)
			(stroke
				(width 0.1)
				(type default)
			)
			(layer "B.Fab")
		)
		(fp_line
			(start 0.7239 1.9939)
			(end -0.7239 1.9939)
			(stroke
				(width 0.1)
				(type default)
			)
			(layer "B.Fab")
		)
		(pad "1" smd rect
			(at 0 0 180)
			(size 1.27 1.016)
			(layers "B.Cu" "B.Mask" "B.Paste")
			(net "PVCCIN_CPU1")
		)
		(pad "2" smd rect
			(at 0 1.778 180)
			(size 1.27 1.016)
			(layers "B.Cu" "B.Mask" "B.Paste")
			(net "GND")
		)
		(zone
			(layer "B.Cu")
			(hatch none 0.5)
			(connect_pads
				(clearance 0)
			)
			(min_thickness 0.25)
			(keepout
				(tracks not_allowed)
				(vias allowed)
				(pads allowed)
				(copperpour not_allowed)
				(footprints allowed)
			)
			(placement
				(enabled no)
				(sheetname "")
			)
			(fill
				(thermal_gap 0.5)
				(thermal_bridge_width 0.5)
				(island_removal_mode 0)
			)
			(polygon
				(pts
					(xy 96.012254 -73.00214) (xy 94.742254 -73.00214) (xy 94.742254 -72.24014) (xy 96.012254 -72.24014)
				)
			)
		)
	)
	(footprint ""
		(layer "B.Cu")
		(at 347.346778 -101.449632 -90)
		(property "Reference" "C7C20"
			(at 0 0 90)
			(layer "B.SilkS")
			(hide yes)
			(effects
				(font
					(size 1.27 1.27)
				)
				(justify mirror)
			)
		)
		(property "Value" "*"
			(at -1.1811 -2.8194 270)
			(unlocked yes)
			(layer "B.Fab")
			(hide yes)
			(effects
				(font
					(size 1.27 1.016)
					(thickness 0.1524)
				)
				(justify mirror)
			)
		)
		(property "Device Type" "SC1U10V2KX-4-GP_SMD-BCG6-SC1U1A"
			(at -1.1811 -4.3434 270)
			(unlocked yes)
			(layer "B.Fab")
			(hide yes)
			(effects
				(font
					(size 1.27 1.016)
					(thickness 0.1524)
				)
				(justify mirror)
			)
		)
		(duplicate_pad_numbers_are_jumpers no)
		(fp_rect
			(start 0.4318 0.9525)
			(end -0.4318 -0.9525)
			(stroke
				(width 0)
				(type default)
			)
			(fill no)
			(layer "B.CrtYd")
		)
		(fp_rect
			(start 0.4318 0.9525)
			(end -0.4318 -0.9525)
			(stroke
				(width 0)
				(type default)
			)
			(fill no)
			(layer "B.Fab")
		)
		(pad "1" smd custom
			(at 0 -0.4445 90)
			(size 0.1524 0.1524)
			(layers "B.Cu" "B.Mask" "B.Paste")
			(net "P5V_STBY")
			(options
				(clearance outline)
				(anchor circle)
			)
			(primitives
				(gr_poly
					(pts
						(arc
							(start 0.3048 0.2032)
							(mid 0.275042 0.275042)
							(end 0.2032 0.3048)
						)
						(arc
							(start -0.2032 0.3048)
							(mid -0.275042 0.275042)
							(end -0.3048 0.2032)
						)
						(arc
							(start -0.3048 -0.2032)
							(mid -0.275042 -0.275042)
							(end -0.2032 -0.3048)
						)
						(arc
							(start 0.2032 -0.3048)
							(mid 0.275042 -0.275042)
							(end 0.3048 -0.2032)
						)
					)
					(width 0)
					(fill yes)
				)
			)
		)
		(pad "2" smd custom
			(at 0 0.4445 90)
			(size 0.1524 0.1524)
			(layers "B.Cu" "B.Mask" "B.Paste")
			(net "GND")
			(options
				(clearance outline)
				(anchor circle)
			)
			(primitives
				(gr_poly
					(pts
						(arc
							(start 0.3048 0.2032)
							(mid 0.275042 0.275042)
							(end 0.2032 0.3048)
						)
						(arc
							(start -0.2032 0.3048)
							(mid -0.275042 0.275042)
							(end -0.3048 0.2032)
						)
						(arc
							(start -0.3048 -0.2032)
							(mid -0.275042 -0.275042)
							(end -0.2032 -0.3048)
						)
						(arc
							(start 0.2032 -0.3048)
							(mid 0.275042 -0.275042)
							(end 0.3048 -0.2032)
						)
					)
					(width 0)
					(fill yes)
				)
			)
		)
	)
	(footprint ""
		(layer "B.Cu")
		(at 23.87854 -87.24138 90)
		(property "Reference" "CR9P1"
			(at 0 0 90)
			(layer "B.SilkS")
			(hide yes)
			(effects
				(font
					(size 1.27 1.27)
				)
				(justify mirror)
			)
		)
		(property "Value" ""
			(at 0 0 90)
			(layer "B.Fab")
			(effects
				(font
					(size 1.27 1.27)
				)
				(justify mirror)
			)
		)
		(duplicate_pad_numbers_are_jumpers no)
		(fp_line
			(start -0.546862 -0.332486)
			(end -0.546862 0.790956)
			(stroke
				(width 0.1524)
				(type default)
			)
			(layer "B.SilkS")
		)
		(fp_line
			(start -0.546862 0.790956)
			(end -1.027684 1.623822)
			(stroke
				(width 0.1524)
				(type default)
			)
			(layer "B.SilkS")
		)
		(fp_line
			(start -1.027684 0.790956)
			(end -0.06604 0.790956)
			(stroke
				(width 0.1524)
				(type default)
			)
			(layer "B.SilkS")
		)
		(fp_line
			(start -0.06604 1.623822)
			(end -0.546862 0.790956)
			(stroke
				(width 0.1524)
				(type default)
			)
			(layer "B.SilkS")
		)
		(fp_line
			(start -0.546862 1.623822)
			(end -0.06604 1.623822)
			(stroke
				(width 0.1524)
				(type default)
			)
			(layer "B.SilkS")
		)
		(fp_line
			(start -1.027684 1.623822)
			(end -0.546862 1.623822)
			(stroke
				(width 0.1524)
				(type default)
			)
			(layer "B.SilkS")
		)
		(fp_line
			(start -0.546862 2.535428)
			(end -0.546862 1.623822)
			(stroke
				(width 0.1524)
				(type default)
			)
			(layer "B.SilkS")
		)
		(fp_poly
			(pts
				(xy 0.67437 0.24384) (xy 0.67437 2.04216) (xy -0.67437 2.04216) (xy -0.67437 0.24384)
			)
			(stroke
				(width 0)
				(type default)
			)
			(fill no)
			(layer "B.CrtYd")
		)
		(fp_line
			(start 0.67437 0.24384)
			(end 0.67437 2.04216)
			(stroke
				(width 0.1)
				(type default)
			)
			(layer "B.Fab")
		)
		(fp_line
			(start -0.67437 0.24384)
			(end 0.67437 0.24384)
			(stroke
				(width 0.1)
				(type default)
			)
			(layer "B.Fab")
		)
		(fp_line
			(start -0.546862 0.790956)
			(end -0.546862 -0.332486)
			(stroke
				(width 0.1)
				(type default)
			)
			(layer "B.Fab")
		)
		(fp_line
			(start -0.546862 0.790956)
			(end -1.027684 1.623822)
			(stroke
				(width 0.1)
				(type default)
			)
			(layer "B.Fab")
		)
		(fp_line
			(start -1.027684 0.790956)
			(end -0.06604 0.790956)
			(stroke
				(width 0.1)
				(type default)
			)
			(layer "B.Fab")
		)
		(fp_line
			(start -0.06604 1.623822)
			(end -0.546862 0.790956)
			(stroke
				(width 0.1)
				(type default)
			)
			(layer "B.Fab")
		)
		(fp_line
			(start -0.546862 1.623822)
			(end -0.546862 2.535428)
			(stroke
				(width 0.1)
				(type default)
			)
			(layer "B.Fab")
		)
		(fp_line
			(start -1.027684 1.623822)
			(end -0.06604 1.623822)
			(stroke
				(width 0.1)
				(type default)
			)
			(layer "B.Fab")
		)
		(fp_line
			(start 0.67437 2.04216)
			(end -0.67437 2.04216)
			(stroke
				(width 0.1)
				(type default)
			)
			(layer "B.Fab")
		)
		(fp_line
			(start -0.67437 2.04216)
			(end -0.67437 0.24384)
			(stroke
				(width 0.1)
				(type default)
			)
			(layer "B.Fab")
		)
		(pad "1" smd rect
			(at 0 0 270)
			(size 0.4064 1.016)
			(layers "B.Cu" "B.Mask" "B.Paste")
			(net "IRQ_UV_DETECT_N")
		)
		(pad "2" smd rect
			(at 0 2.286 270)
			(size 0.4064 1.016)
			(layers "B.Cu" "B.Mask" "B.Paste")
			(net "FM_DISABLE_FAN_N")
		)
	)
	(footprint ""
		(layer "B.Cu")
		(at 382.0922 -137.541)
		(property "Reference" "C3L26"
			(at 0 0 0)
			(layer "B.SilkS")
			(hide yes)
			(effects
				(font
					(size 1.27 1.27)
				)
				(justify mirror)
			)
		)
		(property "Value" ""
			(at 0 0 0)
			(layer "B.Fab")
			(effects
				(font
					(size 1.27 1.27)
				)
				(justify mirror)
			)
		)
		(duplicate_pad_numbers_are_jumpers no)
		(fp_poly
			(pts
				(xy 0.4953 -0.2032) (xy -0.4953 -0.2032) (xy -0.4953 1.6002) (xy 0.4953 1.6002)
			)
			(stroke
				(width 0)
				(type default)
			)
			(fill no)
			(layer "B.CrtYd")
		)
		(fp_line
			(start -0.4953 -0.2032)
			(end -0.4953 1.6002)
			(stroke
				(width 0.1)
				(type default)
			)
			(layer "B.Fab")
		)
		(fp_line
			(start -0.4953 1.6002)
			(end 0.4953 1.6002)
			(stroke
				(width 0.1)
				(type default)
			)
			(layer "B.Fab")
		)
		(fp_line
			(start 0.4953 -0.2032)
			(end -0.4953 -0.2032)
			(stroke
				(width 0.1)
				(type default)
			)
			(layer "B.Fab")
		)
		(fp_line
			(start 0.4953 1.6002)
			(end 0.4953 -0.2032)
			(stroke
				(width 0.1)
				(type default)
			)
			(layer "B.Fab")
		)
		(pad "1" smd rect
			(at 0 0 180)
			(size 0.762 0.889)
			(layers "B.Cu" "B.Mask" "B.Paste")
			(net "PVNN_PCH_STBY")
		)
		(pad "2" smd rect
			(at 0 1.397 180)
			(size 0.762 0.889)
			(layers "B.Cu" "B.Mask" "B.Paste")
			(net "GND")
		)
		(zone
			(layer "B.Cu")
			(hatch none 0.5)
			(connect_pads
				(clearance 0)
			)
			(min_thickness 0.25)
			(keepout
				(tracks not_allowed)
				(vias allowed)
				(pads allowed)
				(copperpour not_allowed)
				(footprints allowed)
			)
			(placement
				(enabled no)
				(sheetname "")
			)
			(fill
				(thermal_gap 0.5)
				(thermal_bridge_width 0.5)
				(island_removal_mode 0)
			)
			(polygon
				(pts
					(xy 382.4732 -137.0965) (xy 381.7112 -137.0965) (xy 381.7112 -136.5885) (xy 382.4732 -136.5885)
				)
			)
		)
	)
	(footprint ""
		(layer "B.Cu")
		(at 429.046894 -16.042894 -90)
		(property "Reference" "R1U36"
			(at 0 0 90)
			(layer "B.SilkS")
			(hide yes)
			(effects
				(font
					(size 1.27 1.27)
				)
				(justify mirror)
			)
		)
		(property "Value" ""
			(at 0 0 90)
			(layer "B.Fab")
			(effects
				(font
					(size 1.27 1.27)
				)
				(justify mirror)
			)
		)
		(duplicate_pad_numbers_are_jumpers no)
		(fp_poly
			(pts
				(xy 0.2794 -0.1016) (xy -0.2794 -0.1016) (xy -0.2794 0.9906) (xy 0.2794 0.9906)
			)
			(stroke
				(width 0)
				(type default)
			)
			(fill no)
			(layer "B.CrtYd")
		)
		(fp_line
			(start -0.2794 0.9906)
			(end -0.2794 -0.1016)
			(stroke
				(width 0.1)
				(type default)
			)
			(layer "B.Fab")
		)
		(fp_line
			(start 0.2794 0.9906)
			(end -0.2794 0.9906)
			(stroke
				(width 0.1)
				(type default)
			)
			(layer "B.Fab")
		)
		(fp_line
			(start -0.2794 -0.1016)
			(end 0.2794 -0.1016)
			(stroke
				(width 0.1)
				(type default)
			)
			(layer "B.Fab")
		)
		(fp_line
			(start 0.2794 -0.1016)
			(end 0.2794 0.9906)
			(stroke
				(width 0.1)
				(type default)
			)
			(layer "B.Fab")
		)
		(pad "1" smd rect
			(at 0 0 90)
			(size 0.508 0.508)
			(layers "B.Cu" "B.Mask" "B.Paste")
			(net "H_CPU1_MEMGHJ_MEMHOT_LVT3_K_N")
		)
		(pad "2" smd rect
			(at 0 0.889 90)
			(size 0.508 0.508)
			(layers "B.Cu" "B.Mask" "B.Paste")
			(net "H_CPU1_MEMGHJ_MEMHOT_LVT3_N")
		)
		(zone
			(layer "B.Cu")
			(hatch none 0.5)
			(connect_pads
				(clearance 0)
			)
			(min_thickness 0.25)
			(keepout
				(tracks not_allowed)
				(vias allowed)
				(pads allowed)
				(copperpour not_allowed)
				(footprints allowed)
			)
			(placement
				(enabled no)
				(sheetname "")
			)
			(fill
				(thermal_gap 0.5)
				(thermal_bridge_width 0.5)
				(island_removal_mode 0)
			)
			(polygon
				(pts
					(xy 428.411894 -15.788894) (xy 428.411894 -16.296894) (xy 428.792894 -16.296894) (xy 428.792894 -15.788894)
				)
			)
		)
		(zone
			(layer "B.Cu")
			(hatch none 0.5)
			(connect_pads
				(clearance 0)
			)
			(min_thickness 0.25)
			(keepout
				(tracks allowed)
				(vias not_allowed)
				(pads allowed)
				(copperpour not_allowed)
				(footprints allowed)
			)
			(placement
				(enabled no)
				(sheetname "")
			)
			(fill
				(thermal_gap 0.5)
				(thermal_bridge_width 0.5)
				(island_removal_mode 0)
			)
			(polygon
				(pts
					(xy 428.792894 -15.788894) (xy 428.792894 -16.296894) (xy 428.411894 -16.296894) (xy 428.411894 -15.788894)
				)
			)
		)
	)
)
